# T6G (Grand Teton) — schematic netlist excerpt (pin names and nets, part order shuffled) for the footprints in the layout excerpt that follows; sources: Cadence DE-HDL packaged netlist, KiCad conversion of 04192023_DAF0TMB3IC0_F0TG_MB_C_brd_V02_OCP.brd

R8351  Q_RES  0 5% CHIP  pkg 0402LF  page 55 : A = CLK_100M_CPU1_CLK13_R_DN ; B = CLK_100M_CPU1_CLK13_DN
R3169  Q_RES  0 5% CHIP  pkg 0402LF  page 137 : A = OCP_V3_2_ISO_BIF0_EN ; B = OCP_V3_2_BIF0_R_N
H128  HOLE  EMPTY  pkg TH  page 230 : \1\ = GND

(kicad_pcb
	(version 20260206)
	(generator "pcbnew")
	(generator_version "10.0")
	(general
		(thickness 1.6)
		(legacy_teardrops no)
	)
	(paper "A4")
	(title_block
		(title "04192023_DAF0TMB3IC0_F0TG_MB_C_brd_V02_OCP.brd")
		(comment 1 "Grand Teton / footprints 2021-2023 of 8354")
	)
	(layers
		(0 "F.Cu" signal "TOP")
		(4 "In1.Cu" signal "GND")
		(6 "In2.Cu" signal "IN1")
		(8 "In3.Cu" signal "GND1")
		(10 "In4.Cu" signal "IN2")
		(12 "In5.Cu" signal "GND2")
		(14 "In6.Cu" signal "IN3")
		(16 "In7.Cu" signal "GND3")
		(18 "In8.Cu" signal "VCC")
		(20 "In9.Cu" signal "VCC1")
		(22 "In10.Cu" signal "GND4")
		(24 "In11.Cu" signal "IN4")
		(26 "In12.Cu" signal "GND5")
		(28 "In13.Cu" signal "IN5")
		(30 "In14.Cu" signal "GND6")
		(32 "In15.Cu" signal "IN6")
		(34 "In16.Cu" signal "GND7")
		(2 "B.Cu" signal "BOTTOM")
		(9 "F.Adhes" user "F.Adhesive")
		(11 "B.Adhes" user "B.Adhesive")
		(13 "F.Paste" user "Package Geometry/Pastemask Top")
		(15 "B.Paste" user "Package Geometry/Pastemask Bottom")
		(5 "F.SilkS" user "Ref Des/Silkscreen Top")
		(7 "B.SilkS" user "Ref Des/Silkscreen Bottom")
		(1 "F.Mask" user "Board Geometry/Soldermask Top")
		(3 "B.Mask" user "Board Geometry/Soldermask Bottom")
		(17 "Dwgs.User" user "User.Drawings")
		(19 "Cmts.User" user "User.Comments")
		(21 "Eco1.User" user "User.Eco1")
		(23 "Eco2.User" user "User.Eco2")
		(25 "Edge.Cuts" user "Board Geometry/Outline")
		(27 "Margin" user)
		(31 "F.CrtYd" user "Package Geometry/Place Bound Top")
		(29 "B.CrtYd" user "Package Geometry/Place Bound Bottom")
		(35 "F.Fab" user "Ref Des/Assembly Top")
		(33 "B.Fab" user "Ref Des/Assembly Bottom")
	)
	(footprint ""
		(layer "F.Cu")
		(at 120.523 -321.691 90)
		(property "Reference" "R8351"
			(at 0 0 90)
			(layer "F.SilkS")
			(hide yes)
			(effects
				(font
					(size 1.27 1.27)
				)
			)
		)
		(property "Value" ""
			(at 0 0 90)
			(layer "F.Fab")
			(effects
				(font
					(size 1.27 1.27)
				)
			)
		)
		(duplicate_pad_numbers_are_jumpers no)
		(fp_line
			(start 0.7874 -0.4064)
			(end 0.7874 -0.0762)
			(stroke
				(width 0.1524)
				(type default)
			)
			(layer "F.SilkS")
		)
		(fp_line
			(start -0.7874 -0.4064)
			(end 0.7874 -0.4064)
			(stroke
				(width 0.1524)
				(type default)
			)
			(layer "F.SilkS")
		)
		(fp_line
			(start -0.7874 -0.0254)
			(end -0.7874 -0.4064)
			(stroke
				(width 0.1524)
				(type default)
			)
			(layer "F.SilkS")
		)
		(fp_line
			(start 0.4064 0.4064)
			(end -0.381 0.4064)
			(stroke
				(width 0.1524)
				(type default)
			)
			(layer "F.SilkS")
		)
		(fp_line
			(start -0.12065 -0.305054)
			(end -0.12065 -0.2794)
			(stroke
				(width 0.1)
				(type default)
			)
			(layer "F.Fab")
		)
		(fp_line
			(start -0.67945 -0.305054)
			(end -0.12065 -0.305054)
			(stroke
				(width 0.1)
				(type default)
			)
			(layer "F.Fab")
		)
		(fp_line
			(start 0.67945 -0.3048)
			(end 0.67945 0.3048)
			(stroke
				(width 0.1)
				(type default)
			)
			(layer "F.Fab")
		)
		(fp_line
			(start 0.12065 -0.3048)
			(end 0.67945 -0.3048)
			(stroke
				(width 0.1)
				(type default)
			)
			(layer "F.Fab")
		)
		(fp_line
			(start 0.12065 -0.2794)
			(end 0.12065 -0.3048)
			(stroke
				(width 0.1)
				(type default)
			)
			(layer "F.Fab")
		)
		(fp_line
			(start -0.12065 -0.2794)
			(end 0.12065 -0.2794)
			(stroke
				(width 0.1)
				(type default)
			)
			(layer "F.Fab")
		)
		(fp_line
			(start 0.120396 0.2794)
			(end -0.12065 0.2794)
			(stroke
				(width 0.1)
				(type default)
			)
			(layer "F.Fab")
		)
		(fp_line
			(start -0.12065 0.2794)
			(end -0.12065 0.3048)
			(stroke
				(width 0.1)
				(type default)
			)
			(layer "F.Fab")
		)
		(fp_line
			(start 0.67945 0.3048)
			(end 0.120396 0.3048)
			(stroke
				(width 0.1)
				(type default)
			)
			(layer "F.Fab")
		)
		(fp_line
			(start 0.120396 0.3048)
			(end 0.120396 0.2794)
			(stroke
				(width 0.1)
				(type default)
			)
			(layer "F.Fab")
		)
		(fp_line
			(start -0.12065 0.3048)
			(end -0.67945 0.3048)
			(stroke
				(width 0.1)
				(type default)
			)
			(layer "F.Fab")
		)
		(fp_line
			(start -0.67945 0.3048)
			(end -0.67945 -0.305054)
			(stroke
				(width 0.1)
				(type default)
			)
			(layer "F.Fab")
		)
		(pad "1" smd circle
			(at -0.40005 0 90)
			(size 0 0)
			(layers "F.Cu" "F.Mask" "F.Paste")
			(net "CLK_100M_CPU1_CLK13_R_DN")
		)
		(pad "2" smd circle
			(at 0.40005 0 90)
			(size 0 0)
			(layers "F.Cu" "F.Mask" "F.Paste")
			(net "CLK_100M_CPU1_CLK13_DN")
		)
	)
	(footprint ""
		(layer "F.Cu")
		(at 371.298724 -435.600094)
		(property "Reference" "H128"
			(at -5.98043 -4.94538 0)
			(unlocked yes)
			(layer "F.SilkS")
			(effects
				(font
					(size 0.7874 0.5842)
					(thickness 0.1524)
				)
				(justify left)
			)
		)
		(property "Value" ""
			(at 0 0 0)
			(layer "F.Fab")
			(effects
				(font
					(size 1.27 1.27)
				)
			)
		)
		(duplicate_pad_numbers_are_jumpers no)
		(pad "1" thru_hole circle
			(at 0 0)
			(size 10.0076 10.0076)
			(drill 5.6134)
			(layers "*.Cu" "*.Mask")
			(remove_unused_layers no)
			(net "GND")
			(clearance -1.9431)
		)
	)
	(footprint ""
		(layer "F.Cu")
		(at 63.059564 -16.220948 -90)
		(property "Reference" "R3169"
			(at 0 0 270)
			(layer "F.SilkS")
			(hide yes)
			(effects
				(font
					(size 1.27 1.27)
				)
			)
		)
		(property "Value" ""
			(at 0 0 270)
			(layer "F.Fab")
			(effects
				(font
					(size 1.27 1.27)
				)
			)
		)
		(duplicate_pad_numbers_are_jumpers no)
		(fp_line
			(start -0.7874 0.4064)
			(end -0.7874 -0.4064)
			(stroke
				(width 0.1524)
				(type default)
			)
			(layer "F.SilkS")
		)
		(fp_line
			(start 0.7874 0.4064)
			(end -0.7874 0.4064)
			(stroke
				(width 0.1524)
				(type default)
			)
			(layer "F.SilkS")
		)
		(fp_line
			(start -0.7874 -0.4064)
			(end 0.7874 -0.4064)
			(stroke
				(width 0.1524)
				(type default)
			)
			(layer "F.SilkS")
		)
		(fp_line
			(start 0.7874 -0.4064)
			(end 0.7874 0.4064)
			(stroke
				(width 0.1524)
				(type default)
			)
			(layer "F.SilkS")
		)
		(fp_line
			(start -0.67945 0.3048)
			(end -0.67945 -0.305054)
			(stroke
				(width 0.1)
				(type default)
			)
			(layer "F.Fab")
		)
		(fp_line
			(start -0.12065 0.3048)
			(end -0.67945 0.3048)
			(stroke
				(width 0.1)
				(type default)
			)
			(layer "F.Fab")
		)
		(fp_line
			(start 0.120396 0.3048)
			(end 0.120396 0.2794)
			(stroke
				(width 0.1)
				(type default)
			)
			(layer "F.Fab")
		)
		(fp_line
			(start 0.67945 0.3048)
			(end 0.120396 0.3048)
			(stroke
				(width 0.1)
				(type default)
			)
			(layer "F.Fab")
		)
		(fp_line
			(start -0.12065 0.2794)
			(end -0.12065 0.3048)
			(stroke
				(width 0.1)
				(type default)
			)
			(layer "F.Fab")
		)
		(fp_line
			(start 0.120396 0.2794)
			(end -0.12065 0.2794)
			(stroke
				(width 0.1)
				(type default)
			)
			(layer "F.Fab")
		)
		(fp_line
			(start -0.12065 -0.2794)
			(end 0.12065 -0.2794)
			(stroke
				(width 0.1)
				(type default)
			)
			(layer "F.Fab")
		)
		(fp_line
			(start 0.12065 -0.2794)
			(end 0.12065 -0.3048)
			(stroke
				(width 0.1)
				(type default)
			)
			(layer "F.Fab")
		)
		(fp_line
			(start 0.12065 -0.3048)
			(end 0.67945 -0.3048)
			(stroke
				(width 0.1)
				(type default)
			)
			(layer "F.Fab")
		)
		(fp_line
			(start 0.67945 -0.3048)
			(end 0.67945 0.3048)
			(stroke
				(width 0.1)
				(type default)
			)
			(layer "F.Fab")
		)
		(fp_line
			(start -0.67945 -0.305054)
			(end -0.12065 -0.305054)
			(stroke
				(width 0.1)
				(type default)
			)
			(layer "F.Fab")
		)
		(fp_line
			(start -0.12065 -0.305054)
			(end -0.12065 -0.2794)
			(stroke
				(width 0.1)
				(type default)
			)
			(layer "F.Fab")
		)
		(pad "1" smd circle
			(at -0.40005 0 270)
			(size 0 0)
			(layers "F.Cu" "F.Mask" "F.Paste")
			(net "OCP_V3_2_ISO_BIF0_EN")
		)
		(pad "2" smd circle
			(at 0.40005 0 270)
			(size 0 0)
			(layers "F.Cu" "F.Mask" "F.Paste")
			(net "OCP_V3_2_BIF0_R_N")
		)
	)
)
